(kicad_pcb
	(version 20260206)
	(generator "pcbnew")
	(generator_version "10.0")
	(general
		(thickness 1.6)
		(legacy_teardrops no)
	)
	(paper "A4")
	(title_block
		(title "04192023_DAF0TMB3IC0_F0TG_MB_C_brd_V02_OCP.brd")
		(comment 1 "Grand Teton / footprints 3664-3670 of 8354")
	)
	(layers
		(0 "F.Cu" signal "TOP")
		(4 "In1.Cu" signal "GND")
		(6 "In2.Cu" signal "IN1")
		(8 "In3.Cu" signal "GND1")
		(10 "In4.Cu" signal "IN2")
		(12 "In5.Cu" signal "GND2")
		(14 "In6.Cu" signal "IN3")
		(16 "In7.Cu" signal "GND3")
		(18 "In8.Cu" signal "VCC")
		(20 "In9.Cu" signal "VCC1")
		(22 "In10.Cu" signal "GND4")
		(24 "In11.Cu" signal "IN4")
		(26 "In12.Cu" signal "GND5")
		(28 "In13.Cu" signal "IN5")
		(30 "In14.Cu" signal "GND6")
		(32 "In15.Cu" signal "IN6")
		(34 "In16.Cu" signal "GND7")
		(2 "B.Cu" signal "BOTTOM")
		(9 "F.Adhes" user "F.Adhesive")
		(11 "B.Adhes" user "B.Adhesive")
		(13 "F.Paste" user "Package Geometry/Pastemask Top")
		(15 "B.Paste" user "Package Geometry/Pastemask Bottom")
		(5 "F.SilkS" user "Ref Des/Silkscreen Top")
		(7 "B.SilkS" user "Ref Des/Silkscreen Bottom")
		(1 "F.Mask" user "Board Geometry/Soldermask Top")
		(3 "B.Mask" user "Board Geometry/Soldermask Bottom")
		(17 "Dwgs.User" user "User.Drawings")
		(19 "Cmts.User" user "User.Comments")
		(21 "Eco1.User" user "User.Eco1")
		(23 "Eco2.User" user "User.Eco2")
		(25 "Edge.Cuts" user "Board Geometry/Outline")
		(27 "Margin" user)
		(31 "F.CrtYd" user "Package Geometry/Place Bound Top")
		(29 "B.CrtYd" user "Package Geometry/Place Bound Bottom")
		(35 "F.Fab" user "Ref Des/Assembly Top")
		(33 "B.Fab" user "Ref Des/Assembly Bottom")
	)
	(footprint ""
		(layer "F.Cu")
		(at 442.18352 -434.549296)
		(property "Reference" "Q106"
			(at -1.499616 -2.115566 0)
			(unlocked yes)
			(layer "F.SilkS")
			(effects
				(font
					(size 0.7874 0.5842)
					(thickness 0.1524)
				)
				(justify left)
			)
		)
		(property "Value" ""
			(at 0 0 0)
			(layer "F.Fab")
			(effects
				(font
					(size 1.27 1.27)
				)
			)
		)
		(duplicate_pad_numbers_are_jumpers no)
		(fp_line
			(start -1.332738 -1.100074)
			(end -0.4826 -1.100074)
			(stroke
				(width 0.1524)
				(type default)
			)
			(layer "F.SilkS")
		)
		(fp_line
			(start -1.332738 1.100074)
			(end -1.332738 -1.100074)
			(stroke
				(width 0.1524)
				(type default)
			)
			(layer "F.SilkS")
		)
		(fp_line
			(start -0.4826 -1.100074)
			(end 0 -0.541274)
			(stroke
				(width 0.1524)
				(type default)
			)
			(layer "F.SilkS")
		)
		(fp_line
			(start 0 -0.541274)
			(end 0.4826 -1.100074)
			(stroke
				(width 0.1524)
				(type default)
			)
			(layer "F.SilkS")
		)
		(fp_line
			(start 0.4826 -1.100074)
			(end 1.332738 -1.100074)
			(stroke
				(width 0.1524)
				(type default)
			)
			(layer "F.SilkS")
		)
		(fp_line
			(start 1.332738 -1.100074)
			(end 1.332738 1.100074)
			(stroke
				(width 0.1524)
				(type default)
			)
			(layer "F.SilkS")
		)
		(fp_line
			(start 1.332738 1.100074)
			(end -1.332738 1.100074)
			(stroke
				(width 0.1524)
				(type default)
			)
			(layer "F.SilkS")
		)
		(fp_poly
			(pts
				(xy -1.533144 -0.649986) (xy -2.2352 -0.298958) (xy -2.2352 -1.001014)
			)
			(stroke
				(width 0)
				(type default)
			)
			(fill yes)
			(layer "F.SilkS")
		)
		(fp_line
			(start -0.674878 -1.100074)
			(end 0.674878 -1.100074)
			(stroke
				(width 0.1)
				(type default)
			)
			(layer "F.Fab")
		)
		(fp_line
			(start -0.674878 1.100074)
			(end -0.674878 -1.100074)
			(stroke
				(width 0.1)
				(type default)
			)
			(layer "F.Fab")
		)
		(fp_line
			(start 0.674878 -1.100074)
			(end 0.674878 1.100074)
			(stroke
				(width 0.1)
				(type default)
			)
			(layer "F.Fab")
		)
		(fp_line
			(start 0.674878 1.100074)
			(end -0.674878 1.100074)
			(stroke
				(width 0.1)
				(type default)
			)
			(layer "F.Fab")
		)
		(fp_poly
			(pts
				(xy -2.2352 -0.298958) (xy -2.2352 -1.001014) (xy -1.533144 -0.649986)
			)
			(stroke
				(width 0)
				(type default)
			)
			(fill yes)
			(layer "F.Fab")
		)
		(pad "1" smd rect
			(at -0.94996 -0.649986 90)
			(size 0.4318 0.508)
			(layers "F.Cu" "F.Mask" "F.Paste")
			(net "GND")
		)
		(pad "2" smd rect
			(at -0.94996 0 90)
			(size 0.4318 0.508)
			(layers "F.Cu" "F.Mask" "F.Paste")
			(net "GPU_WP_HW_CTRL_N")
		)
		(pad "3" smd rect
			(at -0.94996 0.649986 90)
			(size 0.4318 0.508)
			(layers "F.Cu" "F.Mask" "F.Paste")
			(net "GPU_WP_HW_CTRL_ISO_N")
		)
		(pad "4" smd rect
			(at 0.94996 0.649986 90)
			(size 0.4318 0.508)
			(layers "F.Cu" "F.Mask" "F.Paste")
			(net "GND")
		)
		(pad "5" smd rect
			(at 0.94996 0 90)
			(size 0.4318 0.508)
			(layers "F.Cu" "F.Mask" "F.Paste")
			(net "GPU_WP_HW_CTRL_ISO")
		)
		(pad "6" smd rect
			(at 0.94996 -0.649986 90)
			(size 0.4318 0.508)
			(layers "F.Cu" "F.Mask" "F.Paste")
			(net "GPU_WP_HW_CTRL_ISO")
		)
	)
	(footprint ""
		(layer "F.Cu")
		(at 93.717364 -408.517344 -90)
		(property "Reference" "C6660"
			(at 0 0 270)
			(layer "F.SilkS")
			(hide yes)
			(effects
				(font
					(size 1.27 1.27)
				)
			)
		)
		(property "Value" ""
			(at 0 0 270)
			(layer "F.Fab")
			(effects
				(font
					(size 1.27 1.27)
				)
			)
		)
		(duplicate_pad_numbers_are_jumpers no)
		(fp_line
			(start -0.299974 0.150114)
			(end -0.299974 -0.150114)
			(stroke
				(width 0.1)
				(type default)
			)
			(layer "F.Fab")
		)
		(fp_line
			(start 0.299974 0.150114)
			(end -0.299974 0.150114)
			(stroke
				(width 0.1)
				(type default)
			)
			(layer "F.Fab")
		)
		(fp_line
			(start -0.299974 -0.150114)
			(end 0.299974 -0.150114)
			(stroke
				(width 0.1)
				(type default)
			)
			(layer "F.Fab")
		)
		(fp_line
			(start 0.299974 -0.150114)
			(end 0.299974 0.150114)
			(stroke
				(width 0.1)
				(type default)
			)
			(layer "F.Fab")
		)
		(pad "1" smd rect
			(at -0.2667 0 270)
			(size 0.3048 0.381)
			(layers "F.Cu" "F.Mask" "F.Paste")
			(net "P5E_CPU1_P0_TX_BUF_C_DN<15>")
		)
		(pad "2" smd rect
			(at 0.2667 0 270)
			(size 0.3048 0.381)
			(layers "F.Cu" "F.Mask" "F.Paste")
			(net "P5E_CPU1_P0_TX_BUF_DN<15>")
		)
	)
	(footprint ""
		(layer "F.Cu")
		(at 79.523844 -339.644736 90)
		(property "Reference" "PR259"
			(at 0 0 90)
			(layer "F.SilkS")
			(hide yes)
			(effects
				(font
					(size 1.27 1.27)
				)
			)
		)
		(property "Value" ""
			(at 0 0 90)
			(layer "F.Fab")
			(effects
				(font
					(size 1.27 1.27)
				)
			)
		)
		(duplicate_pad_numbers_are_jumpers no)
		(fp_line
			(start 0.7874 -0.4064)
			(end 0.7874 0.4064)
			(stroke
				(width 0.1524)
				(type default)
			)
			(layer "F.SilkS")
		)
		(fp_line
			(start -0.7874 -0.4064)
			(end 0.7874 -0.4064)
			(stroke
				(width 0.1524)
				(type default)
			)
			(layer "F.SilkS")
		)
		(fp_line
			(start 0.7874 0.4064)
			(end -0.7874 0.4064)
			(stroke
				(width 0.1524)
				(type default)
			)
			(layer "F.SilkS")
		)
		(fp_line
			(start -0.7874 0.4064)
			(end -0.7874 -0.4064)
			(stroke
				(width 0.1524)
				(type default)
			)
			(layer "F.SilkS")
		)
		(fp_line
			(start -0.12065 -0.305054)
			(end -0.12065 -0.2794)
			(stroke
				(width 0.1)
				(type default)
			)
			(layer "F.Fab")
		)
		(fp_line
			(start -0.67945 -0.305054)
			(end -0.12065 -0.305054)
			(stroke
				(width 0.1)
				(type default)
			)
			(layer "F.Fab")
		)
		(fp_line
			(start 0.67945 -0.3048)
			(end 0.67945 0.3048)
			(stroke
				(width 0.1)
				(type default)
			)
			(layer "F.Fab")
		)
		(fp_line
			(start 0.12065 -0.3048)
			(end 0.67945 -0.3048)
			(stroke
				(width 0.1)
				(type default)
			)
			(layer "F.Fab")
		)
		(fp_line
			(start 0.12065 -0.2794)
			(end 0.12065 -0.3048)
			(stroke
				(width 0.1)
				(type default)
			)
			(layer "F.Fab")
		)
		(fp_line
			(start -0.12065 -0.2794)
			(end 0.12065 -0.2794)
			(stroke
				(width 0.1)
				(type default)
			)
			(layer "F.Fab")
		)
		(fp_line
			(start 0.120396 0.2794)
			(end -0.12065 0.2794)
			(stroke
				(width 0.1)
				(type default)
			)
			(layer "F.Fab")
		)
		(fp_line
			(start -0.12065 0.2794)
			(end -0.12065 0.3048)
			(stroke
				(width 0.1)
				(type default)
			)
			(layer "F.Fab")
		)
		(fp_line
			(start 0.67945 0.3048)
			(end 0.120396 0.3048)
			(stroke
				(width 0.1)
				(type default)
			)
			(layer "F.Fab")
		)
		(fp_line
			(start 0.120396 0.3048)
			(end 0.120396 0.2794)
			(stroke
				(width 0.1)
				(type default)
			)
			(layer "F.Fab")
		)
		(fp_line
			(start -0.12065 0.3048)
			(end -0.67945 0.3048)
			(stroke
				(width 0.1)
				(type default)
			)
			(layer "F.Fab")
		)
		(fp_line
			(start -0.67945 0.3048)
			(end -0.67945 -0.305054)
			(stroke
				(width 0.1)
				(type default)
			)
			(layer "F.Fab")
		)
		(pad "1" smd circle
			(at -0.40005 0 90)
			(size 0 0)
			(layers "F.Cu" "F.Mask" "F.Paste")
			(net "SW_PVDDCR_CPU1_P1_BOOT2")
		)
		(pad "2" smd circle
			(at 0.40005 0 90)
			(size 0 0)
			(layers "F.Cu" "F.Mask" "F.Paste")
			(net "SW_PVDDCR_CPU1_P1_BOOT2_R")
		)
	)
	(footprint ""
		(layer "F.Cu")
		(at 384.760978 -182.745634 90)
		(property "Reference" "PC548_C0P0_3"
			(at 0 0 90)
			(layer "F.SilkS")
			(hide yes)
			(effects
				(font
					(size 1.27 1.27)
				)
			)
		)
		(property "Value" ""
			(at 0 0 90)
			(layer "F.Fab")
			(effects
				(font
					(size 1.27 1.27)
				)
			)
		)
		(duplicate_pad_numbers_are_jumpers no)
		(fp_line
			(start 0.7874 -0.4064)
			(end 0.7874 0.4064)
			(stroke
				(width 0.1524)
				(type default)
			)
			(layer "F.SilkS")
		)
		(fp_line
			(start -0.7874 -0.4064)
			(end 0.7874 -0.4064)
			(stroke
				(width 0.1524)
				(type default)
			)
			(layer "F.SilkS")
		)
		(fp_line
			(start 0.7874 0.4064)
			(end -0.7874 0.4064)
			(stroke
				(width 0.1524)
				(type default)
			)
			(layer "F.SilkS")
		)
		(fp_line
			(start -0.7874 0.4064)
			(end -0.7874 -0.4064)
			(stroke
				(width 0.1524)
				(type default)
			)
			(layer "F.SilkS")
		)
		(fp_line
			(start -0.12065 -0.305054)
			(end -0.12065 -0.2794)
			(stroke
				(width 0.1)
				(type default)
			)
			(layer "F.Fab")
		)
		(fp_line
			(start -0.67945 -0.305054)
			(end -0.12065 -0.305054)
			(stroke
				(width 0.1)
				(type default)
			)
			(layer "F.Fab")
		)
		(fp_line
			(start 0.67945 -0.3048)
			(end 0.67945 0.3048)
			(stroke
				(width 0.1)
				(type default)
			)
			(layer "F.Fab")
		)
		(fp_line
			(start 0.12065 -0.3048)
			(end 0.67945 -0.3048)
			(stroke
				(width 0.1)
				(type default)
			)
			(layer "F.Fab")
		)
		(fp_line
			(start 0.12065 -0.2794)
			(end 0.12065 -0.3048)
			(stroke
				(width 0.1)
				(type default)
			)
			(layer "F.Fab")
		)
		(fp_line
			(start -0.12065 -0.2794)
			(end 0.12065 -0.2794)
			(stroke
				(width 0.1)
				(type default)
			)
			(layer "F.Fab")
		)
		(fp_line
			(start 0.120396 0.2794)
			(end -0.12065 0.2794)
			(stroke
				(width 0.1)
				(type default)
			)
			(layer "F.Fab")
		)
		(fp_line
			(start -0.12065 0.2794)
			(end -0.12065 0.3048)
			(stroke
				(width 0.1)
				(type default)
			)
			(layer "F.Fab")
		)
		(fp_line
			(start 0.67945 0.3048)
			(end 0.120396 0.3048)
			(stroke
				(width 0.1)
				(type default)
			)
			(layer "F.Fab")
		)
		(fp_line
			(start 0.120396 0.3048)
			(end 0.120396 0.2794)
			(stroke
				(width 0.1)
				(type default)
			)
			(layer "F.Fab")
		)
		(fp_line
			(start -0.12065 0.3048)
			(end -0.67945 0.3048)
			(stroke
				(width 0.1)
				(type default)
			)
			(layer "F.Fab")
		)
		(fp_line
			(start -0.67945 0.3048)
			(end -0.67945 -0.305054)
			(stroke
				(width 0.1)
				(type default)
			)
			(layer "F.Fab")
		)
		(pad "1" smd circle
			(at -0.40005 0 90)
			(size 0 0)
			(layers "F.Cu" "F.Mask" "F.Paste")
			(net "PVDDCR_CPU0_P0_PVCC")
		)
		(pad "2" smd circle
			(at 0.40005 0 90)
			(size 0 0)
			(layers "F.Cu" "F.Mask" "F.Paste")
			(net "GND")
		)
	)
	(footprint ""
		(layer "F.Cu")
		(at 443.859666 -380.13767 -90)
		(property "Reference" "PC6571"
			(at 4.75234 2.153666 0)
			(unlocked yes)
			(layer "F.SilkS")
			(effects
				(font
					(size 0.7874 0.5842)
					(thickness 0.1524)
				)
				(justify left)
			)
		)
		(property "Value" ""
			(at 0 0 270)
			(layer "F.Fab")
			(effects
				(font
					(size 1.27 1.27)
				)
			)
		)
		(duplicate_pad_numbers_are_jumpers no)
		(fp_line
			(start -1.988058 2.750058)
			(end 2.750058 2.750058)
			(stroke
				(width 0.1524)
				(type default)
			)
			(layer "F.SilkS")
		)
		(fp_line
			(start 2.750058 2.750058)
			(end 2.750058 0.9398)
			(stroke
				(width 0.1524)
				(type default)
			)
			(layer "F.SilkS")
		)
		(fp_line
			(start -2.750058 1.988058)
			(end -1.988058 2.750058)
			(stroke
				(width 0.1524)
				(type default)
			)
			(layer "F.SilkS")
		)
		(fp_line
			(start -2.750058 0.9398)
			(end -2.750058 1.988058)
			(stroke
				(width 0.1524)
				(type default)
			)
			(layer "F.SilkS")
		)
		(fp_line
			(start 2.750058 -0.9398)
			(end 2.750058 -2.750058)
			(stroke
				(width 0.1524)
				(type default)
			)
			(layer "F.SilkS")
		)
		(fp_line
			(start -2.750058 -1.988058)
			(end -2.750058 -0.9398)
			(stroke
				(width 0.1524)
				(type default)
			)
			(layer "F.SilkS")
		)
		(fp_line
			(start -1.988058 -2.750058)
			(end -2.750058 -1.988058)
			(stroke
				(width 0.1524)
				(type default)
			)
			(layer "F.SilkS")
		)
		(fp_line
			(start 2.750058 -2.750058)
			(end -1.988058 -2.750058)
			(stroke
				(width 0.1524)
				(type default)
			)
			(layer "F.SilkS")
		)
		(fp_line
			(start -2.750058 2.750058)
			(end 2.750058 2.750058)
			(stroke
				(width 0.1)
				(type default)
			)
			(layer "F.Fab")
		)
		(fp_line
			(start 2.750058 2.750058)
			(end 2.750058 -2.750058)
			(stroke
				(width 0.1)
				(type default)
			)
			(layer "F.Fab")
		)
		(fp_line
			(start -2.750058 -2.750058)
			(end -2.750058 2.750058)
			(stroke
				(width 0.1)
				(type default)
			)
			(layer "F.Fab")
		)
		(fp_line
			(start 2.750058 -2.750058)
			(end -2.750058 -2.750058)
			(stroke
				(width 0.1)
				(type default)
			)
			(layer "F.Fab")
		)
		(pad "1" smd rect
			(at -2.199894 0)
			(size 1.6002 3.0226)
			(layers "F.Cu" "F.Mask" "F.Paste")
			(net "P0V9_CPU0_RT_2D")
		)
		(pad "2" smd rect
			(at 2.199894 0)
			(size 1.6002 3.0226)
			(layers "F.Cu" "F.Mask" "F.Paste")
			(net "GND")
		)
	)
	(footprint ""
		(layer "F.Cu")
		(at 24.759158 -402.599906 90)
		(property "Reference" "PL6510"
			(at -3.592576 -2.153158 0)
			(unlocked yes)
			(layer "F.SilkS")
			(effects
				(font
					(size 0.7874 0.5842)
					(thickness 0.1524)
				)
				(justify left)
			)
		)
		(property "Value" ""
			(at 0 0 90)
			(layer "F.Fab")
			(effects
				(font
					(size 1.27 1.27)
				)
			)
		)
		(duplicate_pad_numbers_are_jumpers no)
		(fp_line
			(start 2.249932 -2.249932)
			(end 2.249932 -1.3843)
			(stroke
				(width 0.1524)
				(type default)
			)
			(layer "F.SilkS")
		)
		(fp_line
			(start -2.249932 -2.249932)
			(end 2.249932 -2.249932)
			(stroke
				(width 0.1524)
				(type default)
			)
			(layer "F.SilkS")
		)
		(fp_line
			(start -2.249932 -1.3843)
			(end -2.249932 -2.249932)
			(stroke
				(width 0.1524)
				(type default)
			)
			(layer "F.SilkS")
		)
		(fp_line
			(start 2.249932 1.3843)
			(end 2.249932 2.249932)
			(stroke
				(width 0.1524)
				(type default)
			)
			(layer "F.SilkS")
		)
		(fp_line
			(start 2.249932 2.249932)
			(end -2.249932 2.249932)
			(stroke
				(width 0.1524)
				(type default)
			)
			(layer "F.SilkS")
		)
		(fp_line
			(start -2.249932 2.249932)
			(end -2.249932 1.3843)
			(stroke
				(width 0.1524)
				(type default)
			)
			(layer "F.SilkS")
		)
		(fp_line
			(start 2.249932 -2.249932)
			(end 2.249932 2.249932)
			(stroke
				(width 0.1)
				(type default)
			)
			(layer "F.Fab")
		)
		(fp_line
			(start -2.249932 -2.249932)
			(end 2.249932 -2.249932)
			(stroke
				(width 0.1)
				(type default)
			)
			(layer "F.Fab")
		)
		(fp_line
			(start 2.249932 2.249932)
			(end -2.249932 2.249932)
			(stroke
				(width 0.1)
				(type default)
			)
			(layer "F.Fab")
		)
		(fp_line
			(start -2.249932 2.249932)
			(end -2.249932 -2.249932)
			(stroke
				(width 0.1)
				(type default)
			)
			(layer "F.Fab")
		)
		(pad "1" smd rect
			(at -1.82499 0 90)
			(size 1.0668 2.5146)
			(layers "F.Cu" "F.Mask" "F.Paste")
			(net "SW_P12V_AUX_P0V9_RETIMER_CPU1_FLT")
		)
		(pad "2" smd rect
			(at 1.82499 0 90)
			(size 1.0668 2.5146)
			(layers "F.Cu" "F.Mask" "F.Paste")
			(net "P12V_AUX")
		)
	)
	(footprint ""
		(layer "F.Cu")
		(at 52.22748 -29.657548 90)
		(property "Reference" "U225"
			(at -2.483612 3.139948 90)
			(unlocked yes)
			(layer "F.SilkS")
			(effects
				(font
					(size 0.7874 0.5842)
					(thickness 0.1524)
				)
				(justify left)
			)
		)
		(property "Value" ""
			(at 0 0 90)
			(layer "F.Fab")
			(effects
				(font
					(size 1.27 1.27)
				)
			)
		)
		(duplicate_pad_numbers_are_jumpers no)
		(fp_line
			(start 1.400048 -1.100074)
			(end -1.400048 -1.100074)
			(stroke
				(width 0.1524)
				(type default)
			)
			(layer "F.SilkS")
		)
		(fp_line
			(start 1.400048 -1.100074)
			(end 1.400048 1.100074)
			(stroke
				(width 0.1524)
				(type default)
			)
			(layer "F.SilkS")
		)
		(fp_line
			(start 1.400048 1.100074)
			(end -1.400048 1.100074)
			(stroke
				(width 0.1524)
				(type default)
			)
			(layer "F.SilkS")
		)
		(fp_line
			(start -1.400048 1.100074)
			(end -1.400048 -1.100074)
			(stroke
				(width 0.1524)
				(type default)
			)
			(layer "F.SilkS")
		)
		(fp_poly
			(pts
				(xy -2.606548 -0.141986) (xy -2.606548 -1.157986) (xy -1.590548 -0.649986)
			)
			(stroke
				(width 0)
				(type default)
			)
			(fill yes)
			(layer "F.SilkS")
		)
		(fp_line
			(start 0.674878 -1.100074)
			(end 0.674878 1.100074)
			(stroke
				(width 0.1)
				(type default)
			)
			(layer "F.Fab")
		)
		(fp_line
			(start -0.674878 -1.100074)
			(end 0.674878 -1.100074)
			(stroke
				(width 0.1)
				(type default)
			)
			(layer "F.Fab")
		)
		(fp_line
			(start 0.674878 1.100074)
			(end -0.674878 1.100074)
			(stroke
				(width 0.1)
				(type default)
			)
			(layer "F.Fab")
		)
		(fp_line
			(start -0.674878 1.100074)
			(end -0.674878 -1.100074)
			(stroke
				(width 0.1)
				(type default)
			)
			(layer "F.Fab")
		)
		(fp_poly
			(pts
				(xy -1.590548 -0.649986) (xy -2.606548 -1.157986) (xy -2.606548 -0.141986)
			)
			(stroke
				(width 0)
				(type default)
			)
			(fill yes)
			(layer "F.Fab")
		)
		(pad "1" smd rect
			(at -0.94996 -0.649986)
			(size 0.4318 0.6096)
			(layers "F.Cu" "F.Mask" "F.Paste")
			(net "OCP_V3_2_AUX_PWR_EN_R3")
		)
		(pad "2" smd rect
			(at -0.94996 0)
			(size 0.4318 0.6096)
			(layers "F.Cu" "F.Mask" "F.Paste")
			(net "RST_SMB_SWITCH_N")
		)
		(pad "3" smd rect
			(at -0.94996 0.649986)
			(size 0.4318 0.6096)
			(layers "F.Cu" "F.Mask" "F.Paste")
			(net "GND")
		)
		(pad "4" smd rect
			(at 0.94996 0.649986)
			(size 0.4318 0.6096)
			(layers "F.Cu" "F.Mask" "F.Paste")
			(net "RST_HP_OCP_V3_2_R_N")
		)
		(pad "5" smd rect
			(at 0.94996 -0.649986)
			(size 0.4318 0.6096)
			(layers "F.Cu" "F.Mask" "F.Paste")
			(net "P3V3_AUX")
		)
	)
)
